# S9S_MB_2U (Grand Teton) — schematic netlist excerpt (pin names and nets, part order shuffled) for the footprints in the layout excerpt that follows; sources: Cadence DE-HDL packaged netlist, KiCad conversion of 03242023_DA0F0TMBIJ0_F0T_Motherboard_J_brd_V01_OCP.brd

R906  Q_RES  33.2 1% CHIP  pkg 0402LF  page 114 : A = PWRGD_CHG_CPU1_DIMM2 ; B = PWRGD_FAIL_CPU1_GH
R568  Q_RES  4.7K 1% CHIP  pkg 0402LF  page 206 : A = PD_DB2000_SMB_SA1 ; B = GND

(kicad_pcb
	(version 20260206)
	(generator "pcbnew")
	(generator_version "10.0")
	(general
		(thickness 1.6)
		(legacy_teardrops no)
	)
	(paper "A4")
	(title_block
		(title "03242023_DA0F0TMBIJ0_F0T_Motherboard_J_brd_V01_OCP.brd")
		(comment 1 "Grand Teton / footprints 4688-4689 of 6105")
	)
	(layers
		(0 "F.Cu" signal "TOP")
		(4 "In1.Cu" signal "GND")
		(6 "In2.Cu" signal "IN1")
		(8 "In3.Cu" signal "GND1")
		(10 "In4.Cu" signal "IN2")
		(12 "In5.Cu" signal "GND2")
		(14 "In6.Cu" signal "IN3")
		(16 "In7.Cu" signal "GND3")
		(18 "In8.Cu" signal "VCC")
		(20 "In9.Cu" signal "VCC1")
		(22 "In10.Cu" signal "GND4")
		(24 "In11.Cu" signal "IN4")
		(26 "In12.Cu" signal "GND5")
		(28 "In13.Cu" signal "IN5")
		(30 "In14.Cu" signal "GND6")
		(32 "In15.Cu" signal "IN6")
		(34 "In16.Cu" signal "GND7")
		(2 "B.Cu" signal "BOTTOM")
		(9 "F.Adhes" user "F.Adhesive")
		(11 "B.Adhes" user "B.Adhesive")
		(13 "F.Paste" user "Package Geometry/Pastemask Top")
		(15 "B.Paste" user "Package Geometry/Pastemask Bottom")
		(5 "F.SilkS" user "Ref Des/Silkscreen Top")
		(7 "B.SilkS" user "Ref Des/Silkscreen Bottom")
		(1 "F.Mask" user "Board Geometry/Soldermask Top")
		(3 "B.Mask" user "Board Geometry/Soldermask Bottom")
		(17 "Dwgs.User" user "User.Drawings")
		(19 "Cmts.User" user "User.Comments")
		(21 "Eco1.User" user "User.Eco1")
		(23 "Eco2.User" user "User.Eco2")
		(25 "Edge.Cuts" user "Board Geometry/Outline")
		(27 "Margin" user)
		(31 "F.CrtYd" user "Package Geometry/Place Bound Top")
		(29 "B.CrtYd" user "Package Geometry/Place Bound Bottom")
		(35 "F.Fab" user "Ref Des/Assembly Top")
		(33 "B.Fab" user "Ref Des/Assembly Bottom")
	)
	(footprint ""
		(layer "B.Cu")
		(at 243.99748 -128.336548 -90)
		(property "Reference" "R568"
			(at 0 0 90)
			(layer "B.SilkS")
			(hide yes)
			(effects
				(font
					(size 1.27 1.27)
				)
				(justify mirror)
			)
		)
		(property "Value" ""
			(at 0 0 90)
			(layer "B.Fab")
			(effects
				(font
					(size 1.27 1.27)
				)
				(justify mirror)
			)
		)
		(duplicate_pad_numbers_are_jumpers no)
		(fp_line
			(start -0.7874 0.4064)
			(end 0.7874 0.4064)
			(stroke
				(width 0.1524)
				(type default)
			)
			(layer "B.SilkS")
		)
		(fp_line
			(start 0.7874 0.4064)
			(end 0.7874 -0.4064)
			(stroke
				(width 0.1524)
				(type default)
			)
			(layer "B.SilkS")
		)
		(fp_line
			(start -0.7874 -0.4064)
			(end -0.7874 0.4064)
			(stroke
				(width 0.1524)
				(type default)
			)
			(layer "B.SilkS")
		)
		(fp_line
			(start 0.7874 -0.4064)
			(end -0.7874 -0.4064)
			(stroke
				(width 0.1524)
				(type default)
			)
			(layer "B.SilkS")
		)
		(fp_line
			(start -0.67945 0.3048)
			(end -0.120396 0.3048)
			(stroke
				(width 0.1)
				(type default)
			)
			(layer "B.Fab")
		)
		(fp_line
			(start -0.120396 0.3048)
			(end -0.120396 0.2794)
			(stroke
				(width 0.1)
				(type default)
			)
			(layer "B.Fab")
		)
		(fp_line
			(start 0.12065 0.3048)
			(end 0.67945 0.3048)
			(stroke
				(width 0.1)
				(type default)
			)
			(layer "B.Fab")
		)
		(fp_line
			(start 0.67945 0.3048)
			(end 0.67945 -0.305054)
			(stroke
				(width 0.1)
				(type default)
			)
			(layer "B.Fab")
		)
		(fp_line
			(start -0.120396 0.2794)
			(end 0.12065 0.2794)
			(stroke
				(width 0.1)
				(type default)
			)
			(layer "B.Fab")
		)
		(fp_line
			(start 0.12065 0.2794)
			(end 0.12065 0.3048)
			(stroke
				(width 0.1)
				(type default)
			)
			(layer "B.Fab")
		)
		(fp_line
			(start -0.12065 -0.2794)
			(end -0.12065 -0.3048)
			(stroke
				(width 0.1)
				(type default)
			)
			(layer "B.Fab")
		)
		(fp_line
			(start 0.12065 -0.2794)
			(end -0.12065 -0.2794)
			(stroke
				(width 0.1)
				(type default)
			)
			(layer "B.Fab")
		)
		(fp_line
			(start -0.67945 -0.3048)
			(end -0.67945 0.3048)
			(stroke
				(width 0.1)
				(type default)
			)
			(layer "B.Fab")
		)
		(fp_line
			(start -0.12065 -0.3048)
			(end -0.67945 -0.3048)
			(stroke
				(width 0.1)
				(type default)
			)
			(layer "B.Fab")
		)
		(fp_line
			(start 0.12065 -0.305054)
			(end 0.12065 -0.2794)
			(stroke
				(width 0.1)
				(type default)
			)
			(layer "B.Fab")
		)
		(fp_line
			(start 0.67945 -0.305054)
			(end 0.12065 -0.305054)
			(stroke
				(width 0.1)
				(type default)
			)
			(layer "B.Fab")
		)
		(pad "1" smd circle
			(at 0.40005 0 90)
			(size 0 0)
			(layers "B.Cu" "B.Mask" "B.Paste")
			(net "PD_DB2000_SMB_SA1")
		)
		(pad "2" smd circle
			(at -0.40005 0 90)
			(size 0 0)
			(layers "B.Cu" "B.Mask" "B.Paste")
			(net "GND")
		)
	)
	(footprint ""
		(layer "B.Cu")
		(at 193.501518 -319.423288 180)
		(property "Reference" "R906"
			(at 0 0 0)
			(layer "B.SilkS")
			(hide yes)
			(effects
				(font
					(size 1.27 1.27)
				)
				(justify mirror)
			)
		)
		(property "Value" ""
			(at 0 0 0)
			(layer "B.Fab")
			(effects
				(font
					(size 1.27 1.27)
				)
				(justify mirror)
			)
		)
		(duplicate_pad_numbers_are_jumpers no)
		(fp_line
			(start 0.7874 0.4064)
			(end 0.7874 -0.4064)
			(stroke
				(width 0.1524)
				(type default)
			)
			(layer "B.SilkS")
		)
		(fp_line
			(start 0.7874 -0.4064)
			(end -0.7874 -0.4064)
			(stroke
				(width 0.1524)
				(type default)
			)
			(layer "B.SilkS")
		)
		(fp_line
			(start -0.7874 0.4064)
			(end 0.7874 0.4064)
			(stroke
				(width 0.1524)
				(type default)
			)
			(layer "B.SilkS")
		)
		(fp_line
			(start -0.7874 -0.4064)
			(end -0.7874 0.4064)
			(stroke
				(width 0.1524)
				(type default)
			)
			(layer "B.SilkS")
		)
		(fp_line
			(start 0.67945 0.3048)
			(end 0.67945 -0.305054)
			(stroke
				(width 0.1)
				(type default)
			)
			(layer "B.Fab")
		)
		(fp_line
			(start 0.67945 -0.305054)
			(end 0.12065 -0.305054)
			(stroke
				(width 0.1)
				(type default)
			)
			(layer "B.Fab")
		)
		(fp_line
			(start 0.12065 0.3048)
			(end 0.67945 0.3048)
			(stroke
				(width 0.1)
				(type default)
			)
			(layer "B.Fab")
		)
		(fp_line
			(start 0.12065 0.2794)
			(end 0.12065 0.3048)
			(stroke
				(width 0.1)
				(type default)
			)
			(layer "B.Fab")
		)
		(fp_line
			(start 0.12065 -0.2794)
			(end -0.12065 -0.2794)
			(stroke
				(width 0.1)
				(type default)
			)
			(layer "B.Fab")
		)
		(fp_line
			(start 0.12065 -0.305054)
			(end 0.12065 -0.2794)
			(stroke
				(width 0.1)
				(type default)
			)
			(layer "B.Fab")
		)
		(fp_line
			(start -0.120396 0.3048)
			(end -0.120396 0.2794)
			(stroke
				(width 0.1)
				(type default)
			)
			(layer "B.Fab")
		)
		(fp_line
			(start -0.120396 0.2794)
			(end 0.12065 0.2794)
			(stroke
				(width 0.1)
				(type default)
			)
			(layer "B.Fab")
		)
		(fp_line
			(start -0.12065 -0.2794)
			(end -0.12065 -0.3048)
			(stroke
				(width 0.1)
				(type default)
			)
			(layer "B.Fab")
		)
		(fp_line
			(start -0.12065 -0.3048)
			(end -0.67945 -0.3048)
			(stroke
				(width 0.1)
				(type default)
			)
			(layer "B.Fab")
		)
		(fp_line
			(start -0.67945 0.3048)
			(end -0.120396 0.3048)
			(stroke
				(width 0.1)
				(type default)
			)
			(layer "B.Fab")
		)
		(fp_line
			(start -0.67945 -0.3048)
			(end -0.67945 0.3048)
			(stroke
				(width 0.1)
				(type default)
			)
			(layer "B.Fab")
		)
		(pad "1" smd circle
			(at 0.40005 0)
			(size 0 0)
			(layers "B.Cu" "B.Mask" "B.Paste")
			(net "PWRGD_CHG_CPU1_DIMM2")
		)
		(pad "2" smd circle
			(at -0.40005 0)
			(size 0 0)
			(layers "B.Cu" "B.Mask" "B.Paste")
			(net "PWRGD_FAIL_CPU1_GH")
		)
	)
)
